(kicad_pcb
	(version 20260206)
	(generator "pcbnew")
	(generator_version "10.0")
	(general
		(thickness 1.6)
		(legacy_teardrops no)
	)
	(paper "A4")
	(title_block
		(title "01162023_DA0F0TEBIF0_F0T_Expander_BD_F_brd_V02_OCP.brd")
		(comment 1 "Grand Teton / footprints 8828-8835 of 9728")
	)
	(layers
		(0 "F.Cu" signal "TOP")
		(4 "In1.Cu" signal "GND")
		(6 "In2.Cu" signal "VCC")
		(8 "In3.Cu" signal "VCC1")
		(10 "In4.Cu" signal "GND1")
		(12 "In5.Cu" signal "IN1")
		(14 "In6.Cu" signal "GND2")
		(16 "In7.Cu" signal "IN2")
		(18 "In8.Cu" signal "GND3")
		(20 "In9.Cu" signal "IN3")
		(22 "In10.Cu" signal "GND4")
		(24 "In11.Cu" signal "IN4")
		(26 "In12.Cu" signal "GND5")
		(28 "In13.Cu" signal "IN5")
		(30 "In14.Cu" signal "GND6")
		(32 "In15.Cu" signal "IN6")
		(34 "In16.Cu" signal "GND7")
		(2 "B.Cu" signal "BOTTOM")
		(9 "F.Adhes" user "F.Adhesive")
		(11 "B.Adhes" user "B.Adhesive")
		(13 "F.Paste" user "Package Geometry/Pastemask Top")
		(15 "B.Paste" user "Package Geometry/Pastemask Bottom")
		(5 "F.SilkS" user "Ref Des/Silkscreen Top")
		(7 "B.SilkS" user "Ref Des/Silkscreen Bottom")
		(1 "F.Mask" user "Board Geometry/Soldermask Top")
		(3 "B.Mask" user "Board Geometry/Soldermask Bottom")
		(17 "Dwgs.User" user "User.Drawings")
		(19 "Cmts.User" user "User.Comments")
		(21 "Eco1.User" user "User.Eco1")
		(23 "Eco2.User" user "User.Eco2")
		(25 "Edge.Cuts" user "Board Geometry/Outline")
		(27 "Margin" user)
		(31 "F.CrtYd" user "Package Geometry/Place Bound Top")
		(29 "B.CrtYd" user "Package Geometry/Place Bound Bottom")
		(35 "F.Fab" user "Ref Des/Assembly Top")
		(33 "B.Fab" user "Ref Des/Assembly Bottom")
	)
	(footprint ""
		(layer "B.Cu")
		(at 395.915388 -360.376724 180)
		(property "Reference" "R6297"
			(at 0 0 0)
			(layer "B.SilkS")
			(hide yes)
			(effects
				(font
					(size 1.27 1.27)
				)
				(justify mirror)
			)
		)
		(property "Value" ""
			(at 0 0 0)
			(layer "B.Fab")
			(effects
				(font
					(size 1.27 1.27)
				)
				(justify mirror)
			)
		)
		(duplicate_pad_numbers_are_jumpers no)
		(fp_line
			(start 0.7874 0.4064)
			(end 0.7874 -0.4064)
			(stroke
				(width 0.1524)
				(type default)
			)
			(layer "B.SilkS")
		)
		(fp_line
			(start 0.7874 -0.4064)
			(end -0.7874 -0.4064)
			(stroke
				(width 0.1524)
				(type default)
			)
			(layer "B.SilkS")
		)
		(fp_line
			(start -0.7874 0.4064)
			(end 0.7874 0.4064)
			(stroke
				(width 0.1524)
				(type default)
			)
			(layer "B.SilkS")
		)
		(fp_line
			(start -0.7874 -0.4064)
			(end -0.7874 0.4064)
			(stroke
				(width 0.1524)
				(type default)
			)
			(layer "B.SilkS")
		)
		(fp_line
			(start 0.67945 0.3048)
			(end 0.67945 -0.305054)
			(stroke
				(width 0.1)
				(type default)
			)
			(layer "B.Fab")
		)
		(fp_line
			(start 0.67945 -0.305054)
			(end 0.12065 -0.305054)
			(stroke
				(width 0.1)
				(type default)
			)
			(layer "B.Fab")
		)
		(fp_line
			(start 0.12065 0.3048)
			(end 0.67945 0.3048)
			(stroke
				(width 0.1)
				(type default)
			)
			(layer "B.Fab")
		)
		(fp_line
			(start 0.12065 0.2794)
			(end 0.12065 0.3048)
			(stroke
				(width 0.1)
				(type default)
			)
			(layer "B.Fab")
		)
		(fp_line
			(start 0.12065 -0.2794)
			(end -0.12065 -0.2794)
			(stroke
				(width 0.1)
				(type default)
			)
			(layer "B.Fab")
		)
		(fp_line
			(start 0.12065 -0.305054)
			(end 0.12065 -0.2794)
			(stroke
				(width 0.1)
				(type default)
			)
			(layer "B.Fab")
		)
		(fp_line
			(start -0.120396 0.3048)
			(end -0.120396 0.2794)
			(stroke
				(width 0.1)
				(type default)
			)
			(layer "B.Fab")
		)
		(fp_line
			(start -0.120396 0.2794)
			(end 0.12065 0.2794)
			(stroke
				(width 0.1)
				(type default)
			)
			(layer "B.Fab")
		)
		(fp_line
			(start -0.12065 -0.2794)
			(end -0.12065 -0.3048)
			(stroke
				(width 0.1)
				(type default)
			)
			(layer "B.Fab")
		)
		(fp_line
			(start -0.12065 -0.3048)
			(end -0.67945 -0.3048)
			(stroke
				(width 0.1)
				(type default)
			)
			(layer "B.Fab")
		)
		(fp_line
			(start -0.67945 0.3048)
			(end -0.120396 0.3048)
			(stroke
				(width 0.1)
				(type default)
			)
			(layer "B.Fab")
		)
		(fp_line
			(start -0.67945 -0.3048)
			(end -0.67945 0.3048)
			(stroke
				(width 0.1)
				(type default)
			)
			(layer "B.Fab")
		)
		(pad "1" smd circle
			(at 0.40005 0)
			(size 0 0)
			(layers "B.Cu" "B.Mask" "B.Paste")
			(net "UART_MB_BIC_RX")
		)
		(pad "2" smd circle
			(at -0.40005 0)
			(size 0 0)
			(layers "B.Cu" "B.Mask" "B.Paste")
			(net "GND")
		)
	)
	(footprint ""
		(layer "B.Cu")
		(at 309.741824 -104.120696 180)
		(property "Reference" "R270"
			(at 0 0 0)
			(layer "B.SilkS")
			(hide yes)
			(effects
				(font
					(size 1.27 1.27)
				)
				(justify mirror)
			)
		)
		(property "Value" ""
			(at 0 0 0)
			(layer "B.Fab")
			(effects
				(font
					(size 1.27 1.27)
				)
				(justify mirror)
			)
		)
		(duplicate_pad_numbers_are_jumpers no)
		(fp_line
			(start 0.7874 0.4064)
			(end 0.7874 -0.4064)
			(stroke
				(width 0.1524)
				(type default)
			)
			(layer "B.SilkS")
		)
		(fp_line
			(start 0.7874 -0.4064)
			(end -0.7874 -0.4064)
			(stroke
				(width 0.1524)
				(type default)
			)
			(layer "B.SilkS")
		)
		(fp_line
			(start -0.7874 0.4064)
			(end 0.7874 0.4064)
			(stroke
				(width 0.1524)
				(type default)
			)
			(layer "B.SilkS")
		)
		(fp_line
			(start -0.7874 -0.4064)
			(end -0.7874 0.4064)
			(stroke
				(width 0.1524)
				(type default)
			)
			(layer "B.SilkS")
		)
		(fp_line
			(start 0.67945 0.3048)
			(end 0.67945 -0.305054)
			(stroke
				(width 0.1)
				(type default)
			)
			(layer "B.Fab")
		)
		(fp_line
			(start 0.67945 -0.305054)
			(end 0.12065 -0.305054)
			(stroke
				(width 0.1)
				(type default)
			)
			(layer "B.Fab")
		)
		(fp_line
			(start 0.12065 0.3048)
			(end 0.67945 0.3048)
			(stroke
				(width 0.1)
				(type default)
			)
			(layer "B.Fab")
		)
		(fp_line
			(start 0.12065 0.2794)
			(end 0.12065 0.3048)
			(stroke
				(width 0.1)
				(type default)
			)
			(layer "B.Fab")
		)
		(fp_line
			(start 0.12065 -0.2794)
			(end -0.12065 -0.2794)
			(stroke
				(width 0.1)
				(type default)
			)
			(layer "B.Fab")
		)
		(fp_line
			(start 0.12065 -0.305054)
			(end 0.12065 -0.2794)
			(stroke
				(width 0.1)
				(type default)
			)
			(layer "B.Fab")
		)
		(fp_line
			(start -0.120396 0.3048)
			(end -0.120396 0.2794)
			(stroke
				(width 0.1)
				(type default)
			)
			(layer "B.Fab")
		)
		(fp_line
			(start -0.120396 0.2794)
			(end 0.12065 0.2794)
			(stroke
				(width 0.1)
				(type default)
			)
			(layer "B.Fab")
		)
		(fp_line
			(start -0.12065 -0.2794)
			(end -0.12065 -0.3048)
			(stroke
				(width 0.1)
				(type default)
			)
			(layer "B.Fab")
		)
		(fp_line
			(start -0.12065 -0.3048)
			(end -0.67945 -0.3048)
			(stroke
				(width 0.1)
				(type default)
			)
			(layer "B.Fab")
		)
		(fp_line
			(start -0.67945 0.3048)
			(end -0.120396 0.3048)
			(stroke
				(width 0.1)
				(type default)
			)
			(layer "B.Fab")
		)
		(fp_line
			(start -0.67945 -0.3048)
			(end -0.67945 0.3048)
			(stroke
				(width 0.1)
				(type default)
			)
			(layer "B.Fab")
		)
		(pad "1" smd circle
			(at 0.40005 0)
			(size 0 0)
			(layers "B.Cu" "B.Mask" "B.Paste")
			(net "NCSI_NIC5_CRS_DV")
		)
		(pad "2" smd circle
			(at -0.40005 0)
			(size 0 0)
			(layers "B.Cu" "B.Mask" "B.Paste")
			(net "GND")
		)
	)
	(footprint ""
		(layer "B.Cu")
		(at 118.387114 -257.699764 180)
		(property "Reference" "PC53"
			(at 0 0 0)
			(layer "B.SilkS")
			(hide yes)
			(effects
				(font
					(size 1.27 1.27)
				)
				(justify mirror)
			)
		)
		(property "Value" ""
			(at 0 0 0)
			(layer "B.Fab")
			(effects
				(font
					(size 1.27 1.27)
				)
				(justify mirror)
			)
		)
		(duplicate_pad_numbers_are_jumpers no)
		(fp_line
			(start 0.7874 0.4064)
			(end 0.7874 -0.4064)
			(stroke
				(width 0.1524)
				(type default)
			)
			(layer "B.SilkS")
		)
		(fp_line
			(start 0.7874 -0.4064)
			(end -0.7874 -0.4064)
			(stroke
				(width 0.1524)
				(type default)
			)
			(layer "B.SilkS")
		)
		(fp_line
			(start -0.7874 0.4064)
			(end 0.7874 0.4064)
			(stroke
				(width 0.1524)
				(type default)
			)
			(layer "B.SilkS")
		)
		(fp_line
			(start -0.7874 -0.4064)
			(end -0.7874 0.4064)
			(stroke
				(width 0.1524)
				(type default)
			)
			(layer "B.SilkS")
		)
		(fp_line
			(start 0.67945 0.3048)
			(end 0.67945 -0.305054)
			(stroke
				(width 0.1)
				(type default)
			)
			(layer "B.Fab")
		)
		(fp_line
			(start 0.67945 -0.305054)
			(end 0.12065 -0.305054)
			(stroke
				(width 0.1)
				(type default)
			)
			(layer "B.Fab")
		)
		(fp_line
			(start 0.12065 0.3048)
			(end 0.67945 0.3048)
			(stroke
				(width 0.1)
				(type default)
			)
			(layer "B.Fab")
		)
		(fp_line
			(start 0.12065 0.2794)
			(end 0.12065 0.3048)
			(stroke
				(width 0.1)
				(type default)
			)
			(layer "B.Fab")
		)
		(fp_line
			(start 0.12065 -0.2794)
			(end -0.12065 -0.2794)
			(stroke
				(width 0.1)
				(type default)
			)
			(layer "B.Fab")
		)
		(fp_line
			(start 0.12065 -0.305054)
			(end 0.12065 -0.2794)
			(stroke
				(width 0.1)
				(type default)
			)
			(layer "B.Fab")
		)
		(fp_line
			(start -0.120396 0.3048)
			(end -0.120396 0.2794)
			(stroke
				(width 0.1)
				(type default)
			)
			(layer "B.Fab")
		)
		(fp_line
			(start -0.120396 0.2794)
			(end 0.12065 0.2794)
			(stroke
				(width 0.1)
				(type default)
			)
			(layer "B.Fab")
		)
		(fp_line
			(start -0.12065 -0.2794)
			(end -0.12065 -0.3048)
			(stroke
				(width 0.1)
				(type default)
			)
			(layer "B.Fab")
		)
		(fp_line
			(start -0.12065 -0.3048)
			(end -0.67945 -0.3048)
			(stroke
				(width 0.1)
				(type default)
			)
			(layer "B.Fab")
		)
		(fp_line
			(start -0.67945 0.3048)
			(end -0.120396 0.3048)
			(stroke
				(width 0.1)
				(type default)
			)
			(layer "B.Fab")
		)
		(fp_line
			(start -0.67945 -0.3048)
			(end -0.67945 0.3048)
			(stroke
				(width 0.1)
				(type default)
			)
			(layer "B.Fab")
		)
		(pad "1" smd circle
			(at 0.40005 0)
			(size 0 0)
			(layers "B.Cu" "B.Mask" "B.Paste")
			(net "P0V8_PEX1_TSEN_R")
		)
		(pad "2" smd circle
			(at -0.40005 0)
			(size 0 0)
			(layers "B.Cu" "B.Mask" "B.Paste")
			(net "GND")
		)
	)
	(footprint ""
		(layer "B.Cu")
		(at 127.986536 -215.09482 180)
		(property "Reference" "U107"
			(at 0.195834 1.785874 0)
			(unlocked yes)
			(layer "B.SilkS")
			(effects
				(font
					(size 0.7874 0.5842)
					(thickness 0.1524)
				)
				(justify mirror)
			)
		)
		(property "Value" ""
			(at 0 0 0)
			(layer "B.Fab")
			(effects
				(font
					(size 1.27 1.27)
				)
				(justify mirror)
			)
		)
		(duplicate_pad_numbers_are_jumpers no)
		(fp_line
			(start 1.7272 1.1176)
			(end 1.7272 -1.1176)
			(stroke
				(width 0.1524)
				(type default)
			)
			(layer "B.SilkS")
		)
		(fp_line
			(start 0.254 -1.1176)
			(end 1.7272 -1.1176)
			(stroke
				(width 0.1524)
				(type default)
			)
			(layer "B.SilkS")
		)
		(fp_line
			(start 0 -0.7366)
			(end 0.254 -1.1176)
			(stroke
				(width 0.1524)
				(type default)
			)
			(layer "B.SilkS")
		)
		(fp_line
			(start -0.254 -1.1176)
			(end 0 -0.7366)
			(stroke
				(width 0.1524)
				(type default)
			)
			(layer "B.SilkS")
		)
		(fp_line
			(start -1.7272 1.1176)
			(end 1.7272 1.1176)
			(stroke
				(width 0.1524)
				(type default)
			)
			(layer "B.SilkS")
		)
		(fp_line
			(start -1.7272 -1.1176)
			(end -0.254 -1.1176)
			(stroke
				(width 0.1524)
				(type default)
			)
			(layer "B.SilkS")
		)
		(fp_line
			(start -1.7272 -1.1176)
			(end -1.7272 1.1176)
			(stroke
				(width 0.1524)
				(type default)
			)
			(layer "B.SilkS")
		)
		(fp_poly
			(pts
				(xy 1.9558 -0.649986) (xy 2.7178 -0.268986) (xy 2.7178 -1.030986)
			)
			(stroke
				(width 0)
				(type default)
			)
			(fill yes)
			(layer "B.SilkS")
		)
		(fp_line
			(start 1.5748 1.1176)
			(end -1.5748 1.1176)
			(stroke
				(width 0.1)
				(type default)
			)
			(layer "B.Fab")
		)
		(fp_line
			(start 1.5748 -1.1176)
			(end 1.5748 1.1176)
			(stroke
				(width 0.1)
				(type default)
			)
			(layer "B.Fab")
		)
		(fp_line
			(start -1.5748 1.1176)
			(end -1.5748 -1.1176)
			(stroke
				(width 0.1)
				(type default)
			)
			(layer "B.Fab")
		)
		(fp_line
			(start -1.5748 -1.1176)
			(end 1.5748 -1.1176)
			(stroke
				(width 0.1)
				(type default)
			)
			(layer "B.Fab")
		)
		(fp_poly
			(pts
				(xy 1.9558 -0.649986) (xy 2.7178 -0.268986) (xy 2.7178 -1.030986)
			)
			(stroke
				(width 0)
				(type default)
			)
			(fill yes)
			(layer "B.Fab")
		)
		(pad "1" smd rect
			(at 0.999998 -0.649986 90)
			(size 0.3556 1.1176)
			(layers "B.Cu" "B.Mask" "B.Paste")
			(net "UART_PEX2_CLI_R_TX")
		)
		(pad "2" smd rect
			(at 0.999998 0 90)
			(size 0.3556 1.1176)
			(layers "B.Cu" "B.Mask" "B.Paste")
			(net "GND")
		)
		(pad "3" smd rect
			(at 0.999998 0.649986 90)
			(size 0.3556 1.1176)
			(layers "B.Cu" "B.Mask" "B.Paste")
			(net "UART_PEX3_CLI_R_TX")
		)
		(pad "4" smd rect
			(at -0.999998 0.649986 90)
			(size 0.3556 1.1176)
			(layers "B.Cu" "B.Mask" "B.Paste")
			(net "UART_PEX3_CLI_BUF_R_TX")
		)
		(pad "5" smd rect
			(at -0.999998 0 90)
			(size 0.3556 1.1176)
			(layers "B.Cu" "B.Mask" "B.Paste")
			(net "P1V8_PEX")
		)
		(pad "6" smd rect
			(at -0.999998 -0.649986 90)
			(size 0.3556 1.1176)
			(layers "B.Cu" "B.Mask" "B.Paste")
			(net "UART_PEX2_CLI_BUF_R_TX")
		)
	)
	(footprint ""
		(layer "B.Cu")
		(at 281.399742 -300.174914)
		(property "Reference" "C1619"
			(at 0 0 0)
			(layer "B.SilkS")
			(hide yes)
			(effects
				(font
					(size 1.27 1.27)
				)
				(justify mirror)
			)
		)
		(property "Value" ""
			(at 0 0 0)
			(layer "B.Fab")
			(effects
				(font
					(size 1.27 1.27)
				)
				(justify mirror)
			)
		)
		(duplicate_pad_numbers_are_jumpers no)
		(fp_line
			(start -0.299974 -0.150114)
			(end -0.299974 0.150114)
			(stroke
				(width 0.1)
				(type default)
			)
			(layer "B.Fab")
		)
		(fp_line
			(start -0.299974 0.150114)
			(end 0.299974 0.150114)
			(stroke
				(width 0.1)
				(type default)
			)
			(layer "B.Fab")
		)
		(fp_line
			(start 0.299974 -0.150114)
			(end -0.299974 -0.150114)
			(stroke
				(width 0.1)
				(type default)
			)
			(layer "B.Fab")
		)
		(fp_line
			(start 0.299974 0.150114)
			(end 0.299974 -0.150114)
			(stroke
				(width 0.1)
				(type default)
			)
			(layer "B.Fab")
		)
		(pad "1" smd rect
			(at 0.2667 0 180)
			(size 0.3048 0.381)
			(layers "B.Cu" "B.Mask" "B.Paste")
			(net "P0V8_PEX2")
		)
		(pad "2" smd rect
			(at -0.2667 0 180)
			(size 0.3048 0.381)
			(layers "B.Cu" "B.Mask" "B.Paste")
			(net "GND")
		)
	)
	(footprint ""
		(layer "B.Cu")
		(at 405.575008 -286.399732 90)
		(property "Reference" "C3476"
			(at 0 0 90)
			(layer "B.SilkS")
			(hide yes)
			(effects
				(font
					(size 1.27 1.27)
				)
				(justify mirror)
			)
		)
		(property "Value" ""
			(at 0 0 90)
			(layer "B.Fab")
			(effects
				(font
					(size 1.27 1.27)
				)
				(justify mirror)
			)
		)
		(duplicate_pad_numbers_are_jumpers no)
		(fp_line
			(start 0.299974 -0.150114)
			(end -0.299974 -0.150114)
			(stroke
				(width 0.1)
				(type default)
			)
			(layer "B.Fab")
		)
		(fp_line
			(start -0.299974 -0.150114)
			(end -0.299974 0.150114)
			(stroke
				(width 0.1)
				(type default)
			)
			(layer "B.Fab")
		)
		(fp_line
			(start 0.299974 0.150114)
			(end 0.299974 -0.150114)
			(stroke
				(width 0.1)
				(type default)
			)
			(layer "B.Fab")
		)
		(fp_line
			(start -0.299974 0.150114)
			(end 0.299974 0.150114)
			(stroke
				(width 0.1)
				(type default)
			)
			(layer "B.Fab")
		)
		(pad "1" smd rect
			(at 0.2667 0 270)
			(size 0.3048 0.381)
			(layers "B.Cu" "B.Mask" "B.Paste")
			(net "P1V25_SERDES_VDDPLL_PEX3")
		)
		(pad "2" smd rect
			(at -0.2667 0 270)
			(size 0.3048 0.381)
			(layers "B.Cu" "B.Mask" "B.Paste")
			(net "GND")
		)
	)
	(footprint ""
		(layer "B.Cu")
		(at 51.574954 -293.99992 -90)
		(property "Reference" "C1139"
			(at 0 0 90)
			(layer "B.SilkS")
			(hide yes)
			(effects
				(font
					(size 1.27 1.27)
				)
				(justify mirror)
			)
		)
		(property "Value" ""
			(at 0 0 90)
			(layer "B.Fab")
			(effects
				(font
					(size 1.27 1.27)
				)
				(justify mirror)
			)
		)
		(duplicate_pad_numbers_are_jumpers no)
		(fp_line
			(start -0.299974 0.150114)
			(end 0.299974 0.150114)
			(stroke
				(width 0.1)
				(type default)
			)
			(layer "B.Fab")
		)
		(fp_line
			(start 0.299974 0.150114)
			(end 0.299974 -0.150114)
			(stroke
				(width 0.1)
				(type default)
			)
			(layer "B.Fab")
		)
		(fp_line
			(start -0.299974 -0.150114)
			(end -0.299974 0.150114)
			(stroke
				(width 0.1)
				(type default)
			)
			(layer "B.Fab")
		)
		(fp_line
			(start 0.299974 -0.150114)
			(end -0.299974 -0.150114)
			(stroke
				(width 0.1)
				(type default)
			)
			(layer "B.Fab")
		)
		(pad "1" smd rect
			(at 0.2667 0 90)
			(size 0.3048 0.381)
			(layers "B.Cu" "B.Mask" "B.Paste")
			(net "P0V8_PEX0")
		)
		(pad "2" smd rect
			(at -0.2667 0 90)
			(size 0.3048 0.381)
			(layers "B.Cu" "B.Mask" "B.Paste")
			(net "GND")
		)
	)
	(footprint ""
		(layer "B.Cu")
		(at 397.85544 -150.9776)
		(property "Reference" "R326"
			(at 0 0 0)
			(layer "B.SilkS")
			(hide yes)
			(effects
				(font
					(size 1.27 1.27)
				)
				(justify mirror)
			)
		)
		(property "Value" ""
			(at 0 0 0)
			(layer "B.Fab")
			(effects
				(font
					(size 1.27 1.27)
				)
				(justify mirror)
			)
		)
		(duplicate_pad_numbers_are_jumpers no)
		(fp_line
			(start -0.7874 -0.4064)
			(end -0.7874 0.4064)
			(stroke
				(width 0.1524)
				(type default)
			)
			(layer "B.SilkS")
		)
		(fp_line
			(start -0.7874 0.4064)
			(end 0.7874 0.4064)
			(stroke
				(width 0.1524)
				(type default)
			)
			(layer "B.SilkS")
		)
		(fp_line
			(start 0.7874 -0.4064)
			(end -0.7874 -0.4064)
			(stroke
				(width 0.1524)
				(type default)
			)
			(layer "B.SilkS")
		)
		(fp_line
			(start 0.7874 0.4064)
			(end 0.7874 -0.4064)
			(stroke
				(width 0.1524)
				(type default)
			)
			(layer "B.SilkS")
		)
		(fp_line
			(start -0.67945 -0.3048)
			(end -0.67945 0.3048)
			(stroke
				(width 0.1)
				(type default)
			)
			(layer "B.Fab")
		)
		(fp_line
			(start -0.67945 0.3048)
			(end -0.120396 0.3048)
			(stroke
				(width 0.1)
				(type default)
			)
			(layer "B.Fab")
		)
		(fp_line
			(start -0.12065 -0.3048)
			(end -0.67945 -0.3048)
			(stroke
				(width 0.1)
				(type default)
			)
			(layer "B.Fab")
		)
		(fp_line
			(start -0.12065 -0.2794)
			(end -0.12065 -0.3048)
			(stroke
				(width 0.1)
				(type default)
			)
			(layer "B.Fab")
		)
		(fp_line
			(start -0.120396 0.2794)
			(end 0.12065 0.2794)
			(stroke
				(width 0.1)
				(type default)
			)
			(layer "B.Fab")
		)
		(fp_line
			(start -0.120396 0.3048)
			(end -0.120396 0.2794)
			(stroke
				(width 0.1)
				(type default)
			)
			(layer "B.Fab")
		)
		(fp_line
			(start 0.12065 -0.305054)
			(end 0.12065 -0.2794)
			(stroke
				(width 0.1)
				(type default)
			)
			(layer "B.Fab")
		)
		(fp_line
			(start 0.12065 -0.2794)
			(end -0.12065 -0.2794)
			(stroke
				(width 0.1)
				(type default)
			)
			(layer "B.Fab")
		)
		(fp_line
			(start 0.12065 0.2794)
			(end 0.12065 0.3048)
			(stroke
				(width 0.1)
				(type default)
			)
			(layer "B.Fab")
		)
		(fp_line
			(start 0.12065 0.3048)
			(end 0.67945 0.3048)
			(stroke
				(width 0.1)
				(type default)
			)
			(layer "B.Fab")
		)
		(fp_line
			(start 0.67945 -0.305054)
			(end 0.12065 -0.305054)
			(stroke
				(width 0.1)
				(type default)
			)
			(layer "B.Fab")
		)
		(fp_line
			(start 0.67945 0.3048)
			(end 0.67945 -0.305054)
			(stroke
				(width 0.1)
				(type default)
			)
			(layer "B.Fab")
		)
		(pad "1" smd circle
			(at 0.40005 0 180)
			(size 0 0)
			(layers "B.Cu" "B.Mask" "B.Paste")
			(net "CLK_50M_NIC6_RBT_REF")
		)
		(pad "2" smd circle
			(at -0.40005 0 180)
			(size 0 0)
			(layers "B.Cu" "B.Mask" "B.Paste")
			(net "GND")
		)
	)
)
